(kicad_pcb
	(version 20260206)
	(generator "pcbnew")
	(generator_version "10.0")
	(general
		(thickness 1.6)
		(legacy_teardrops no)
	)
	(paper "A4")
	(title_block
		(title "peb — Lightning_PEB_BRD.brd")
		(comment 1 "Lightning (Wiwynn / Facebook NVMe JBOF) / footprints 2468-2475 of 2563")
	)
	(layers
		(0 "F.Cu" signal "TOP")
		(4 "In1.Cu" signal "L2GND")
		(6 "In2.Cu" signal "L3")
		(8 "In3.Cu" signal "L4VCC")
		(10 "In4.Cu" signal "L5VCC")
		(12 "In5.Cu" signal "L6")
		(14 "In6.Cu" signal "L7GND")
		(2 "B.Cu" signal "BOTTOM")
		(9 "F.Adhes" user "F.Adhesive")
		(11 "B.Adhes" user "B.Adhesive")
		(13 "F.Paste" user "Package Geometry/Pastemask Top")
		(15 "B.Paste" user "Package Geometry/Pastemask Bottom")
		(5 "F.SilkS" user "Ref Des/Silkscreen Top")
		(7 "B.SilkS" user "Ref Des/Silkscreen Bottom")
		(1 "F.Mask" user "Board Geometry/Soldermask Top")
		(3 "B.Mask" user "Board Geometry/Soldermask Bottom")
		(17 "Dwgs.User" user "User.Drawings")
		(19 "Cmts.User" user "User.Comments")
		(21 "Eco1.User" user "User.Eco1")
		(23 "Eco2.User" user "User.Eco2")
		(25 "Edge.Cuts" user "Board Geometry/Outline")
		(27 "Margin" user)
		(31 "F.CrtYd" user "Package Geometry/Place Bound Top")
		(29 "B.CrtYd" user "Package Geometry/Place Bound Bottom")
		(35 "F.Fab" user "Ref Des/Assembly Top")
		(33 "B.Fab" user "Ref Des/Assembly Bottom")
	)
	(footprint ""
		(layer "B.Cu")
		(at 235.331 -69.85 -90)
		(property "Reference" "C494"
			(at 0 0 90)
			(layer "B.SilkS")
			(hide yes)
			(effects
				(font
					(size 1.27 1.27)
				)
				(justify mirror)
			)
		)
		(property "Value" "SC100U4V5MX-1-GP"
			(at 0.0762 -6.1214 270)
			(unlocked yes)
			(layer "B.Fab")
			(hide yes)
			(effects
				(font
					(size 1.016 1.016)
					(thickness 0.1524)
				)
				(justify mirror)
			)
		)
		(property "Device Type" "C805H58"
			(at 0.0762 -8.1534 270)
			(unlocked yes)
			(layer "B.Fab")
			(hide yes)
			(effects
				(font
					(size 1.016 1.016)
					(thickness 0.1524)
				)
				(justify mirror)
			)
		)
		(duplicate_pad_numbers_are_jumpers no)
		(fp_line
			(start -0.635 0)
			(end 0.635 0)
			(stroke
				(width 0.508)
				(type default)
			)
			(layer "B.SilkS")
		)
		(fp_rect
			(start 0.9652 1.778)
			(end -0.9652 -1.778)
			(stroke
				(width 0)
				(type default)
			)
			(fill no)
			(layer "B.CrtYd")
		)
		(fp_poly
			(pts
				(xy 0.9652 -1.778) (xy -0.9652 -1.778) (xy -0.9652 1.778) (xy 0.9652 1.778)
			)
			(stroke
				(width 0)
				(type default)
			)
			(fill no)
			(layer "B.Fab")
		)
		(pad "1" smd rect
			(at 0 -0.9652 90)
			(size 1.397 1.143)
			(layers "B.Cu" "B.Mask" "B.Paste")
			(net "DUT_AVD_TX")
		)
		(pad "2" smd rect
			(at 0 0.9652 90)
			(size 1.397 1.143)
			(layers "B.Cu" "B.Mask" "B.Paste")
			(net "GND")
		)
	)
	(footprint ""
		(layer "B.Cu")
		(at 237.617 -56.9976 90)
		(property "Reference" "C520"
			(at 0 0 90)
			(layer "B.SilkS")
			(hide yes)
			(effects
				(font
					(size 1.27 1.27)
				)
				(justify mirror)
			)
		)
		(property "Value" "SCD1U16V1KX-1-GP"
			(at 2.8321 -1.7399 90)
			(unlocked yes)
			(layer "B.Fab")
			(hide yes)
			(effects
				(font
					(size 1.016 1.016)
					(thickness 0.1524)
				)
				(justify mirror)
			)
		)
		(property "Device Type" "C0201H13"
			(at 2.8321 -3.2639 90)
			(unlocked yes)
			(layer "B.Fab")
			(hide yes)
			(effects
				(font
					(size 1.016 1.016)
					(thickness 0.1524)
				)
				(justify mirror)
			)
		)
		(duplicate_pad_numbers_are_jumpers no)
		(fp_rect
			(start 0.2794 0.6477)
			(end -0.2794 -0.6477)
			(stroke
				(width 0)
				(type default)
			)
			(fill no)
			(layer "B.CrtYd")
		)
		(fp_rect
			(start 0.2794 0.6477)
			(end -0.2794 -0.6477)
			(stroke
				(width 0)
				(type default)
			)
			(fill no)
			(layer "B.Fab")
		)
		(pad "1" smd custom
			(at 0 -0.2794 270)
			(size 0.0762 0.0762)
			(layers "B.Cu" "B.Mask" "B.Paste")
			(net "DUT_AVD_TX")
			(options
				(clearance outline)
				(anchor circle)
			)
			(primitives
				(gr_poly
					(pts
						(arc
							(start 0.1524 0.127)
							(mid 0.137521 0.162921)
							(end 0.1016 0.1778)
						)
						(arc
							(start -0.1016 0.1778)
							(mid -0.137521 0.162921)
							(end -0.1524 0.127)
						)
						(arc
							(start -0.1524 -0.127)
							(mid -0.137521 -0.162921)
							(end -0.1016 -0.1778)
						)
						(arc
							(start 0.1016 -0.1778)
							(mid 0.137521 -0.162921)
							(end 0.1524 -0.127)
						)
					)
					(width 0)
					(fill yes)
				)
			)
		)
		(pad "2" smd custom
			(at 0 0.2794 270)
			(size 0.0762 0.0762)
			(layers "B.Cu" "B.Mask" "B.Paste")
			(net "GND")
			(options
				(clearance outline)
				(anchor circle)
			)
			(primitives
				(gr_poly
					(pts
						(arc
							(start 0.1524 0.127)
							(mid 0.137521 0.162921)
							(end 0.1016 0.1778)
						)
						(arc
							(start -0.1016 0.1778)
							(mid -0.137521 0.162921)
							(end -0.1524 0.127)
						)
						(arc
							(start -0.1524 -0.127)
							(mid -0.137521 -0.162921)
							(end -0.1016 -0.1778)
						)
						(arc
							(start 0.1016 -0.1778)
							(mid 0.137521 -0.162921)
							(end 0.1524 -0.127)
						)
					)
					(width 0)
					(fill yes)
				)
			)
		)
	)
	(footprint ""
		(layer "B.Cu")
		(at 249.555 -54.99227 90)
		(property "Reference" "C488"
			(at 0 0 90)
			(layer "B.SilkS")
			(hide yes)
			(effects
				(font
					(size 1.27 1.27)
				)
				(justify mirror)
			)
		)
		(property "Value" "SCD1U16V1KX-1-GP"
			(at 2.8321 -1.7399 90)
			(unlocked yes)
			(layer "B.Fab")
			(hide yes)
			(effects
				(font
					(size 1.016 1.016)
					(thickness 0.1524)
				)
				(justify mirror)
			)
		)
		(property "Device Type" "C0201H13"
			(at 2.8321 -3.2639 90)
			(unlocked yes)
			(layer "B.Fab")
			(hide yes)
			(effects
				(font
					(size 1.016 1.016)
					(thickness 0.1524)
				)
				(justify mirror)
			)
		)
		(duplicate_pad_numbers_are_jumpers no)
		(fp_rect
			(start 0.2794 0.6477)
			(end -0.2794 -0.6477)
			(stroke
				(width 0)
				(type default)
			)
			(fill no)
			(layer "B.CrtYd")
		)
		(fp_rect
			(start 0.2794 0.6477)
			(end -0.2794 -0.6477)
			(stroke
				(width 0)
				(type default)
			)
			(fill no)
			(layer "B.Fab")
		)
		(pad "1" smd custom
			(at 0 -0.2794 270)
			(size 0.0762 0.0762)
			(layers "B.Cu" "B.Mask" "B.Paste")
			(net "DUT_AVD_PCIE_Q")
			(options
				(clearance outline)
				(anchor circle)
			)
			(primitives
				(gr_poly
					(pts
						(arc
							(start 0.1524 0.127)
							(mid 0.137521 0.162921)
							(end 0.1016 0.1778)
						)
						(arc
							(start -0.1016 0.1778)
							(mid -0.137521 0.162921)
							(end -0.1524 0.127)
						)
						(arc
							(start -0.1524 -0.127)
							(mid -0.137521 -0.162921)
							(end -0.1016 -0.1778)
						)
						(arc
							(start 0.1016 -0.1778)
							(mid 0.137521 -0.162921)
							(end 0.1524 -0.127)
						)
					)
					(width 0)
					(fill yes)
				)
			)
		)
		(pad "2" smd custom
			(at 0 0.2794 270)
			(size 0.0762 0.0762)
			(layers "B.Cu" "B.Mask" "B.Paste")
			(net "GND")
			(options
				(clearance outline)
				(anchor circle)
			)
			(primitives
				(gr_poly
					(pts
						(arc
							(start 0.1524 0.127)
							(mid 0.137521 0.162921)
							(end 0.1016 0.1778)
						)
						(arc
							(start -0.1016 0.1778)
							(mid -0.137521 0.162921)
							(end -0.1524 0.127)
						)
						(arc
							(start -0.1524 -0.127)
							(mid -0.137521 -0.162921)
							(end -0.1016 -0.1778)
						)
						(arc
							(start 0.1016 -0.1778)
							(mid 0.137521 -0.162921)
							(end 0.1524 -0.127)
						)
					)
					(width 0)
					(fill yes)
				)
			)
		)
	)
	(footprint ""
		(layer "B.Cu")
		(at 245.1354 -48.9966 -90)
		(property "Reference" "C446"
			(at 0 0 90)
			(layer "B.SilkS")
			(hide yes)
			(effects
				(font
					(size 1.27 1.27)
				)
				(justify mirror)
			)
		)
		(property "Value" "SCD1U16V1KX-1-GP"
			(at 2.8321 -1.7399 270)
			(unlocked yes)
			(layer "B.Fab")
			(hide yes)
			(effects
				(font
					(size 1.016 1.016)
					(thickness 0.1524)
				)
				(justify mirror)
			)
		)
		(property "Device Type" "C0201H13"
			(at 2.8321 -3.2639 270)
			(unlocked yes)
			(layer "B.Fab")
			(hide yes)
			(effects
				(font
					(size 1.016 1.016)
					(thickness 0.1524)
				)
				(justify mirror)
			)
		)
		(duplicate_pad_numbers_are_jumpers no)
		(fp_rect
			(start 0.2794 0.6477)
			(end -0.2794 -0.6477)
			(stroke
				(width 0)
				(type default)
			)
			(fill no)
			(layer "B.CrtYd")
		)
		(fp_rect
			(start 0.2794 0.6477)
			(end -0.2794 -0.6477)
			(stroke
				(width 0)
				(type default)
			)
			(fill no)
			(layer "B.Fab")
		)
		(pad "1" smd custom
			(at 0 -0.2794 90)
			(size 0.0762 0.0762)
			(layers "B.Cu" "B.Mask" "B.Paste")
			(net "DUT_VDD")
			(options
				(clearance outline)
				(anchor circle)
			)
			(primitives
				(gr_poly
					(pts
						(arc
							(start 0.1524 0.127)
							(mid 0.137521 0.162921)
							(end 0.1016 0.1778)
						)
						(arc
							(start -0.1016 0.1778)
							(mid -0.137521 0.162921)
							(end -0.1524 0.127)
						)
						(arc
							(start -0.1524 -0.127)
							(mid -0.137521 -0.162921)
							(end -0.1016 -0.1778)
						)
						(arc
							(start 0.1016 -0.1778)
							(mid 0.137521 -0.162921)
							(end 0.1524 -0.127)
						)
					)
					(width 0)
					(fill yes)
				)
			)
		)
		(pad "2" smd custom
			(at 0 0.2794 90)
			(size 0.0762 0.0762)
			(layers "B.Cu" "B.Mask" "B.Paste")
			(net "GND")
			(options
				(clearance outline)
				(anchor circle)
			)
			(primitives
				(gr_poly
					(pts
						(arc
							(start 0.1524 0.127)
							(mid 0.137521 0.162921)
							(end 0.1016 0.1778)
						)
						(arc
							(start -0.1016 0.1778)
							(mid -0.137521 0.162921)
							(end -0.1524 0.127)
						)
						(arc
							(start -0.1524 -0.127)
							(mid -0.137521 -0.162921)
							(end -0.1016 -0.1778)
						)
						(arc
							(start 0.1016 -0.1778)
							(mid 0.137521 -0.162921)
							(end 0.1524 -0.127)
						)
					)
					(width 0)
					(fill yes)
				)
			)
		)
	)
	(footprint ""
		(layer "B.Cu")
		(at 120.9548 -96.1898 180)
		(property "Reference" "R432"
			(at 0 0 0)
			(layer "B.SilkS")
			(hide yes)
			(effects
				(font
					(size 1.27 1.27)
				)
				(justify mirror)
			)
		)
		(property "Value" "0R2J-2-GP"
			(at -0.064008 -3.993896 180)
			(unlocked yes)
			(layer "B.Fab")
			(hide yes)
			(effects
				(font
					(size 1.016 1.016)
					(thickness 0.1524)
				)
				(justify mirror)
			)
		)
		(property "Device Type" "R402H16"
			(at -0.064008 -5.517896 180)
			(unlocked yes)
			(layer "B.Fab")
			(hide yes)
			(effects
				(font
					(size 1.016 1.016)
					(thickness 0.1524)
				)
				(justify mirror)
			)
		)
		(duplicate_pad_numbers_are_jumpers no)
		(fp_line
			(start 0.508 -0.9398)
			(end 0.508 0.9398)
			(stroke
				(width 0.1524)
				(type default)
			)
			(layer "B.SilkS")
		)
		(fp_line
			(start -0.508 -0.9398)
			(end 0.508 -0.9398)
			(stroke
				(width 0.1524)
				(type default)
			)
			(layer "B.SilkS")
		)
		(fp_rect
			(start 0.508 0.9398)
			(end -0.508 -0.9398)
			(stroke
				(width 0)
				(type default)
			)
			(fill no)
			(layer "B.CrtYd")
		)
		(fp_rect
			(start 0.508 0.9398)
			(end -0.508 -0.9398)
			(stroke
				(width 0)
				(type default)
			)
			(fill no)
			(layer "B.Fab")
		)
		(pad "1" smd custom
			(at 0 -0.4445)
			(size 0.1397 0.1397)
			(layers "B.Cu" "B.Mask" "B.Paste")
			(net "BMC_I2C10_8536_SDA")
			(options
				(clearance outline)
				(anchor circle)
			)
			(primitives
				(gr_poly
					(pts
						(arc
							(start -0.1778 0.2794)
							(mid -0.249642 0.249642)
							(end -0.2794 0.1778)
						)
						(arc
							(start -0.2794 -0.1778)
							(mid -0.249642 -0.249642)
							(end -0.1778 -0.2794)
						)
						(arc
							(start 0.1778 -0.2794)
							(mid 0.249642 -0.249642)
							(end 0.2794 -0.1778)
						)
						(arc
							(start 0.2794 0.1778)
							(mid 0.249642 0.249642)
							(end 0.1778 0.2794)
						)
					)
					(width 0)
					(fill yes)
				)
			)
		)
		(pad "2" smd custom
			(at 0 0.4445)
			(size 0.1397 0.1397)
			(layers "B.Cu" "B.Mask" "B.Paste")
			(net "TWI_SDA0")
			(options
				(clearance outline)
				(anchor circle)
			)
			(primitives
				(gr_poly
					(pts
						(arc
							(start -0.1778 0.2794)
							(mid -0.249642 0.249642)
							(end -0.2794 0.1778)
						)
						(arc
							(start -0.2794 -0.1778)
							(mid -0.249642 -0.249642)
							(end -0.1778 -0.2794)
						)
						(arc
							(start 0.1778 -0.2794)
							(mid 0.249642 -0.249642)
							(end 0.2794 -0.1778)
						)
						(arc
							(start 0.2794 0.1778)
							(mid 0.249642 0.249642)
							(end 0.1778 0.2794)
						)
					)
					(width 0)
					(fill yes)
				)
			)
		)
	)
	(footprint ""
		(layer "B.Cu")
		(at 265.065002 -0.748792 90)
		(property "Reference" "R204"
			(at 0 0 90)
			(layer "B.SilkS")
			(hide yes)
			(effects
				(font
					(size 1.27 1.27)
				)
				(justify mirror)
			)
		)
		(property "Value" "0R2J-2-GP"
			(at -0.064008 -3.993896 90)
			(unlocked yes)
			(layer "B.Fab")
			(hide yes)
			(effects
				(font
					(size 1.016 1.016)
					(thickness 0.1524)
				)
				(justify mirror)
			)
		)
		(property "Device Type" "R402H16"
			(at -0.064008 -5.517896 90)
			(unlocked yes)
			(layer "B.Fab")
			(hide yes)
			(effects
				(font
					(size 1.016 1.016)
					(thickness 0.1524)
				)
				(justify mirror)
			)
		)
		(duplicate_pad_numbers_are_jumpers no)
		(fp_line
			(start 0.508 -0.9398)
			(end 0.508 0.9398)
			(stroke
				(width 0.1524)
				(type default)
			)
			(layer "B.SilkS")
		)
		(fp_line
			(start -0.508 -0.9398)
			(end 0.508 -0.9398)
			(stroke
				(width 0.1524)
				(type default)
			)
			(layer "B.SilkS")
		)
		(fp_rect
			(start 0.508 0.9398)
			(end -0.508 -0.9398)
			(stroke
				(width 0)
				(type default)
			)
			(fill no)
			(layer "B.CrtYd")
		)
		(fp_rect
			(start 0.508 0.9398)
			(end -0.508 -0.9398)
			(stroke
				(width 0)
				(type default)
			)
			(fill no)
			(layer "B.Fab")
		)
		(pad "1" smd custom
			(at 0 -0.4445 270)
			(size 0.1397 0.1397)
			(layers "B.Cu" "B.Mask" "B.Paste")
			(net "TEMP_SENSOR_C")
			(options
				(clearance outline)
				(anchor circle)
			)
			(primitives
				(gr_poly
					(pts
						(arc
							(start -0.1778 0.2794)
							(mid -0.249642 0.249642)
							(end -0.2794 0.1778)
						)
						(arc
							(start -0.2794 -0.1778)
							(mid -0.249642 -0.249642)
							(end -0.1778 -0.2794)
						)
						(arc
							(start 0.1778 -0.2794)
							(mid 0.249642 -0.249642)
							(end 0.2794 -0.1778)
						)
						(arc
							(start 0.2794 0.1778)
							(mid 0.249642 0.249642)
							(end 0.1778 0.2794)
						)
					)
					(width 0)
					(fill yes)
				)
			)
		)
		(pad "2" smd custom
			(at 0 0.4445 270)
			(size 0.1397 0.1397)
			(layers "B.Cu" "B.Mask" "B.Paste")
			(net "TEMP_SENSOR_DXN_BJT")
			(options
				(clearance outline)
				(anchor circle)
			)
			(primitives
				(gr_poly
					(pts
						(arc
							(start -0.1778 0.2794)
							(mid -0.249642 0.249642)
							(end -0.2794 0.1778)
						)
						(arc
							(start -0.2794 -0.1778)
							(mid -0.249642 -0.249642)
							(end -0.1778 -0.2794)
						)
						(arc
							(start 0.1778 -0.2794)
							(mid 0.249642 -0.249642)
							(end 0.2794 -0.1778)
						)
						(arc
							(start 0.2794 0.1778)
							(mid 0.249642 0.249642)
							(end 0.1778 0.2794)
						)
					)
					(width 0)
					(fill yes)
				)
			)
		)
	)
	(footprint ""
		(layer "B.Cu")
		(at 227.179124 -203.047092 180)
		(property "Reference" "R4136"
			(at 0 0 0)
			(layer "B.SilkS")
			(hide yes)
			(effects
				(font
					(size 1.27 1.27)
				)
				(justify mirror)
			)
		)
		(property "Value" "4K7R2F-GP"
			(at -0.064008 -3.993896 180)
			(unlocked yes)
			(layer "B.Fab")
			(hide yes)
			(effects
				(font
					(size 1.016 1.016)
					(thickness 0.1524)
				)
				(justify mirror)
			)
		)
		(property "Device Type" "R402H16"
			(at -0.064008 -5.517896 180)
			(unlocked yes)
			(layer "B.Fab")
			(hide yes)
			(effects
				(font
					(size 1.016 1.016)
					(thickness 0.1524)
				)
				(justify mirror)
			)
		)
		(duplicate_pad_numbers_are_jumpers no)
		(fp_line
			(start 0.508 -0.9398)
			(end 0.508 0.9398)
			(stroke
				(width 0.1524)
				(type default)
			)
			(layer "B.SilkS")
		)
		(fp_line
			(start -0.508 -0.9398)
			(end 0.508 -0.9398)
			(stroke
				(width 0.1524)
				(type default)
			)
			(layer "B.SilkS")
		)
		(fp_rect
			(start 0.508 0.9398)
			(end -0.508 -0.9398)
			(stroke
				(width 0)
				(type default)
			)
			(fill no)
			(layer "B.CrtYd")
		)
		(fp_rect
			(start 0.508 0.9398)
			(end -0.508 -0.9398)
			(stroke
				(width 0)
				(type default)
			)
			(fill no)
			(layer "B.Fab")
		)
		(pad "1" smd custom
			(at 0 -0.4445)
			(size 0.1397 0.1397)
			(layers "B.Cu" "B.Mask" "B.Paste")
			(net "SSD_ATNLED#12")
			(options
				(clearance outline)
				(anchor circle)
			)
			(primitives
				(gr_poly
					(pts
						(arc
							(start -0.1778 0.2794)
							(mid -0.249642 0.249642)
							(end -0.2794 0.1778)
						)
						(arc
							(start -0.2794 -0.1778)
							(mid -0.249642 -0.249642)
							(end -0.1778 -0.2794)
						)
						(arc
							(start 0.1778 -0.2794)
							(mid 0.249642 -0.249642)
							(end 0.2794 -0.1778)
						)
						(arc
							(start 0.2794 0.1778)
							(mid 0.249642 0.249642)
							(end 0.1778 0.2794)
						)
					)
					(width 0)
					(fill yes)
				)
			)
		)
		(pad "2" smd custom
			(at 0 0.4445)
			(size 0.1397 0.1397)
			(layers "B.Cu" "B.Mask" "B.Paste")
			(net "P3V3_STBY")
			(options
				(clearance outline)
				(anchor circle)
			)
			(primitives
				(gr_poly
					(pts
						(arc
							(start -0.1778 0.2794)
							(mid -0.249642 0.249642)
							(end -0.2794 0.1778)
						)
						(arc
							(start -0.2794 -0.1778)
							(mid -0.249642 -0.249642)
							(end -0.1778 -0.2794)
						)
						(arc
							(start 0.1778 -0.2794)
							(mid 0.249642 -0.249642)
							(end 0.2794 -0.1778)
						)
						(arc
							(start 0.2794 0.1778)
							(mid 0.249642 0.249642)
							(end 0.1778 0.2794)
						)
					)
					(width 0)
					(fill yes)
				)
			)
		)
	)
	(footprint ""
		(layer "B.Cu")
		(at 23.90648 -139.618974 90)
		(property "Reference" "R370"
			(at 0 0 90)
			(layer "B.SilkS")
			(hide yes)
			(effects
				(font
					(size 1.27 1.27)
				)
				(justify mirror)
			)
		)
		(property "Value" "3K3R2F-2-GP"
			(at -0.064008 -3.993896 90)
			(unlocked yes)
			(layer "B.Fab")
			(hide yes)
			(effects
				(font
					(size 1.016 1.016)
					(thickness 0.1524)
				)
				(justify mirror)
			)
		)
		(property "Device Type" "R402H16"
			(at -0.064008 -5.517896 90)
			(unlocked yes)
			(layer "B.Fab")
			(hide yes)
			(effects
				(font
					(size 1.016 1.016)
					(thickness 0.1524)
				)
				(justify mirror)
			)
		)
		(duplicate_pad_numbers_are_jumpers no)
		(fp_line
			(start 0.508 -0.9398)
			(end 0.508 0.9398)
			(stroke
				(width 0.1524)
				(type default)
			)
			(layer "B.SilkS")
		)
		(fp_line
			(start -0.508 -0.9398)
			(end 0.508 -0.9398)
			(stroke
				(width 0.1524)
				(type default)
			)
			(layer "B.SilkS")
		)
		(fp_rect
			(start 0.508 0.9398)
			(end -0.508 -0.9398)
			(stroke
				(width 0)
				(type default)
			)
			(fill no)
			(layer "B.CrtYd")
		)
		(fp_rect
			(start 0.508 0.9398)
			(end -0.508 -0.9398)
			(stroke
				(width 0)
				(type default)
			)
			(fill no)
			(layer "B.Fab")
		)
		(pad "1" smd custom
			(at 0 -0.4445 270)
			(size 0.1397 0.1397)
			(layers "B.Cu" "B.Mask" "B.Paste")
			(net "P3V3_STBY")
			(options
				(clearance outline)
				(anchor circle)
			)
			(primitives
				(gr_poly
					(pts
						(arc
							(start -0.1778 0.2794)
							(mid -0.249642 0.249642)
							(end -0.2794 0.1778)
						)
						(arc
							(start -0.2794 -0.1778)
							(mid -0.249642 -0.249642)
							(end -0.1778 -0.2794)
						)
						(arc
							(start 0.1778 -0.2794)
							(mid 0.249642 -0.249642)
							(end 0.2794 -0.1778)
						)
						(arc
							(start 0.2794 0.1778)
							(mid 0.249642 0.249642)
							(end 0.1778 0.2794)
						)
					)
					(width 0)
					(fill yes)
				)
			)
		)
		(pad "2" smd custom
			(at 0 0.4445 270)
			(size 0.1397 0.1397)
			(layers "B.Cu" "B.Mask" "B.Paste")
			(net "ROMD7")
			(options
				(clearance outline)
				(anchor circle)
			)
			(primitives
				(gr_poly
					(pts
						(arc
							(start -0.1778 0.2794)
							(mid -0.249642 0.249642)
							(end -0.2794 0.1778)
						)
						(arc
							(start -0.2794 -0.1778)
							(mid -0.249642 -0.249642)
							(end -0.1778 -0.2794)
						)
						(arc
							(start 0.1778 -0.2794)
							(mid 0.249642 -0.249642)
							(end 0.2794 -0.1778)
						)
						(arc
							(start 0.2794 0.1778)
							(mid 0.249642 0.249642)
							(end 0.1778 0.2794)
						)
					)
					(width 0)
					(fill yes)
				)
			)
		)
	)
)
